(kicad_pcb
	(version 20260206)
	(generator "pcbnew")
	(generator_version "10.0")
	(general
		(thickness 1.6)
		(legacy_teardrops no)
	)
	(paper "A4")
	(title_block
		(title "04192023_DAF0TMB3IC0_F0TG_MB_C_brd_V02_OCP.brd")
		(comment 1 "Grand Teton / footprints 5120-5125 of 8354")
	)
	(layers
		(0 "F.Cu" signal "TOP")
		(4 "In1.Cu" signal "GND")
		(6 "In2.Cu" signal "IN1")
		(8 "In3.Cu" signal "GND1")
		(10 "In4.Cu" signal "IN2")
		(12 "In5.Cu" signal "GND2")
		(14 "In6.Cu" signal "IN3")
		(16 "In7.Cu" signal "GND3")
		(18 "In8.Cu" signal "VCC")
		(20 "In9.Cu" signal "VCC1")
		(22 "In10.Cu" signal "GND4")
		(24 "In11.Cu" signal "IN4")
		(26 "In12.Cu" signal "GND5")
		(28 "In13.Cu" signal "IN5")
		(30 "In14.Cu" signal "GND6")
		(32 "In15.Cu" signal "IN6")
		(34 "In16.Cu" signal "GND7")
		(2 "B.Cu" signal "BOTTOM")
		(9 "F.Adhes" user "F.Adhesive")
		(11 "B.Adhes" user "B.Adhesive")
		(13 "F.Paste" user "Package Geometry/Pastemask Top")
		(15 "B.Paste" user "Package Geometry/Pastemask Bottom")
		(5 "F.SilkS" user "Ref Des/Silkscreen Top")
		(7 "B.SilkS" user "Ref Des/Silkscreen Bottom")
		(1 "F.Mask" user "Board Geometry/Soldermask Top")
		(3 "B.Mask" user "Board Geometry/Soldermask Bottom")
		(17 "Dwgs.User" user "User.Drawings")
		(19 "Cmts.User" user "User.Comments")
		(21 "Eco1.User" user "User.Eco1")
		(23 "Eco2.User" user "User.Eco2")
		(25 "Edge.Cuts" user "Board Geometry/Outline")
		(27 "Margin" user)
		(31 "F.CrtYd" user "Package Geometry/Place Bound Top")
		(29 "B.CrtYd" user "Package Geometry/Place Bound Bottom")
		(35 "F.Fab" user "Ref Des/Assembly Top")
		(33 "B.Fab" user "Ref Des/Assembly Bottom")
	)
	(footprint ""
		(layer "B.Cu")
		(at 138.65352 -41.781222 180)
		(property "Reference" "C6069"
			(at 0 0 0)
			(layer "B.SilkS")
			(hide yes)
			(effects
				(font
					(size 1.27 1.27)
				)
				(justify mirror)
			)
		)
		(property "Value" ""
			(at 0 0 0)
			(layer "B.Fab")
			(effects
				(font
					(size 1.27 1.27)
				)
				(justify mirror)
			)
		)
		(duplicate_pad_numbers_are_jumpers no)
		(fp_line
			(start 0.7874 0.4064)
			(end 0.7874 -0.4064)
			(stroke
				(width 0.1524)
				(type default)
			)
			(layer "B.SilkS")
		)
		(fp_line
			(start 0.7874 -0.4064)
			(end -0.7874 -0.4064)
			(stroke
				(width 0.1524)
				(type default)
			)
			(layer "B.SilkS")
		)
		(fp_line
			(start -0.7874 0.4064)
			(end 0.7874 0.4064)
			(stroke
				(width 0.1524)
				(type default)
			)
			(layer "B.SilkS")
		)
		(fp_line
			(start -0.7874 -0.4064)
			(end -0.7874 0.4064)
			(stroke
				(width 0.1524)
				(type default)
			)
			(layer "B.SilkS")
		)
		(fp_line
			(start 0.67945 0.3048)
			(end 0.67945 -0.305054)
			(stroke
				(width 0.1)
				(type default)
			)
			(layer "B.Fab")
		)
		(fp_line
			(start 0.67945 -0.305054)
			(end 0.12065 -0.305054)
			(stroke
				(width 0.1)
				(type default)
			)
			(layer "B.Fab")
		)
		(fp_line
			(start 0.12065 0.3048)
			(end 0.67945 0.3048)
			(stroke
				(width 0.1)
				(type default)
			)
			(layer "B.Fab")
		)
		(fp_line
			(start 0.12065 0.2794)
			(end 0.12065 0.3048)
			(stroke
				(width 0.1)
				(type default)
			)
			(layer "B.Fab")
		)
		(fp_line
			(start 0.12065 -0.2794)
			(end -0.12065 -0.2794)
			(stroke
				(width 0.1)
				(type default)
			)
			(layer "B.Fab")
		)
		(fp_line
			(start 0.12065 -0.305054)
			(end 0.12065 -0.2794)
			(stroke
				(width 0.1)
				(type default)
			)
			(layer "B.Fab")
		)
		(fp_line
			(start -0.120396 0.3048)
			(end -0.120396 0.2794)
			(stroke
				(width 0.1)
				(type default)
			)
			(layer "B.Fab")
		)
		(fp_line
			(start -0.120396 0.2794)
			(end 0.12065 0.2794)
			(stroke
				(width 0.1)
				(type default)
			)
			(layer "B.Fab")
		)
		(fp_line
			(start -0.12065 -0.2794)
			(end -0.12065 -0.3048)
			(stroke
				(width 0.1)
				(type default)
			)
			(layer "B.Fab")
		)
		(fp_line
			(start -0.12065 -0.3048)
			(end -0.67945 -0.3048)
			(stroke
				(width 0.1)
				(type default)
			)
			(layer "B.Fab")
		)
		(fp_line
			(start -0.67945 0.3048)
			(end -0.120396 0.3048)
			(stroke
				(width 0.1)
				(type default)
			)
			(layer "B.Fab")
		)
		(fp_line
			(start -0.67945 -0.3048)
			(end -0.67945 0.3048)
			(stroke
				(width 0.1)
				(type default)
			)
			(layer "B.Fab")
		)
		(pad "1" smd circle
			(at 0.40005 0)
			(size 0 0)
			(layers "B.Cu" "B.Mask" "B.Paste")
			(net "P1V2_AUX")
		)
		(pad "2" smd circle
			(at -0.40005 0)
			(size 0 0)
			(layers "B.Cu" "B.Mask" "B.Paste")
			(net "GND")
		)
	)
	(footprint ""
		(layer "B.Cu")
		(at 181.845458 -426.898816 -90)
		(property "Reference" "R6233"
			(at 0 0 90)
			(layer "B.SilkS")
			(hide yes)
			(effects
				(font
					(size 1.27 1.27)
				)
				(justify mirror)
			)
		)
		(property "Value" ""
			(at 0 0 90)
			(layer "B.Fab")
			(effects
				(font
					(size 1.27 1.27)
				)
				(justify mirror)
			)
		)
		(duplicate_pad_numbers_are_jumpers no)
		(fp_line
			(start -0.7874 0.4064)
			(end 0.7874 0.4064)
			(stroke
				(width 0.1524)
				(type default)
			)
			(layer "B.SilkS")
		)
		(fp_line
			(start 0.7874 0.4064)
			(end 0.7874 -0.4064)
			(stroke
				(width 0.1524)
				(type default)
			)
			(layer "B.SilkS")
		)
		(fp_line
			(start -0.7874 -0.4064)
			(end -0.7874 0.4064)
			(stroke
				(width 0.1524)
				(type default)
			)
			(layer "B.SilkS")
		)
		(fp_line
			(start 0.7874 -0.4064)
			(end -0.7874 -0.4064)
			(stroke
				(width 0.1524)
				(type default)
			)
			(layer "B.SilkS")
		)
		(fp_line
			(start -0.67945 0.3048)
			(end -0.120396 0.3048)
			(stroke
				(width 0.1)
				(type default)
			)
			(layer "B.Fab")
		)
		(fp_line
			(start -0.120396 0.3048)
			(end -0.120396 0.2794)
			(stroke
				(width 0.1)
				(type default)
			)
			(layer "B.Fab")
		)
		(fp_line
			(start 0.12065 0.3048)
			(end 0.67945 0.3048)
			(stroke
				(width 0.1)
				(type default)
			)
			(layer "B.Fab")
		)
		(fp_line
			(start 0.67945 0.3048)
			(end 0.67945 -0.305054)
			(stroke
				(width 0.1)
				(type default)
			)
			(layer "B.Fab")
		)
		(fp_line
			(start -0.120396 0.2794)
			(end 0.12065 0.2794)
			(stroke
				(width 0.1)
				(type default)
			)
			(layer "B.Fab")
		)
		(fp_line
			(start 0.12065 0.2794)
			(end 0.12065 0.3048)
			(stroke
				(width 0.1)
				(type default)
			)
			(layer "B.Fab")
		)
		(fp_line
			(start -0.12065 -0.2794)
			(end -0.12065 -0.3048)
			(stroke
				(width 0.1)
				(type default)
			)
			(layer "B.Fab")
		)
		(fp_line
			(start 0.12065 -0.2794)
			(end -0.12065 -0.2794)
			(stroke
				(width 0.1)
				(type default)
			)
			(layer "B.Fab")
		)
		(fp_line
			(start -0.67945 -0.3048)
			(end -0.67945 0.3048)
			(stroke
				(width 0.1)
				(type default)
			)
			(layer "B.Fab")
		)
		(fp_line
			(start -0.12065 -0.3048)
			(end -0.67945 -0.3048)
			(stroke
				(width 0.1)
				(type default)
			)
			(layer "B.Fab")
		)
		(fp_line
			(start 0.12065 -0.305054)
			(end 0.12065 -0.2794)
			(stroke
				(width 0.1)
				(type default)
			)
			(layer "B.Fab")
		)
		(fp_line
			(start 0.67945 -0.305054)
			(end 0.12065 -0.305054)
			(stroke
				(width 0.1)
				(type default)
			)
			(layer "B.Fab")
		)
		(pad "1" smd circle
			(at 0.40005 0 90)
			(size 0 0)
			(layers "B.Cu" "B.Mask" "B.Paste")
			(net "A_HSC_LOW")
		)
		(pad "2" smd circle
			(at -0.40005 0 90)
			(size 0 0)
			(layers "B.Cu" "B.Mask" "B.Paste")
			(net "GND")
		)
	)
	(footprint ""
		(layer "B.Cu")
		(at 386.078476 -395.148562 90)
		(property "Reference" "C1039"
			(at 0 0 90)
			(layer "B.SilkS")
			(hide yes)
			(effects
				(font
					(size 1.27 1.27)
				)
				(justify mirror)
			)
		)
		(property "Value" ""
			(at 0 0 90)
			(layer "B.Fab")
			(effects
				(font
					(size 1.27 1.27)
				)
				(justify mirror)
			)
		)
		(duplicate_pad_numbers_are_jumpers no)
		(fp_line
			(start 0.299974 -0.150114)
			(end -0.299974 -0.150114)
			(stroke
				(width 0.1)
				(type default)
			)
			(layer "B.Fab")
		)
		(fp_line
			(start -0.299974 -0.150114)
			(end -0.299974 0.150114)
			(stroke
				(width 0.1)
				(type default)
			)
			(layer "B.Fab")
		)
		(fp_line
			(start 0.299974 0.150114)
			(end 0.299974 -0.150114)
			(stroke
				(width 0.1)
				(type default)
			)
			(layer "B.Fab")
		)
		(fp_line
			(start -0.299974 0.150114)
			(end 0.299974 0.150114)
			(stroke
				(width 0.1)
				(type default)
			)
			(layer "B.Fab")
		)
		(pad "1" smd rect
			(at 0.2667 0 270)
			(size 0.3048 0.381)
			(layers "B.Cu" "B.Mask" "B.Paste")
			(net "P0V9_CPU0_RT3_2A")
		)
		(pad "2" smd rect
			(at -0.2667 0 270)
			(size 0.3048 0.381)
			(layers "B.Cu" "B.Mask" "B.Paste")
			(net "GND")
		)
	)
	(footprint ""
		(layer "B.Cu")
		(at 421.90289 -426.765974)
		(property "Reference" "U47"
			(at -1.528826 -2.937002 0)
			(unlocked yes)
			(layer "B.SilkS")
			(effects
				(font
					(size 0.7874 0.5842)
					(thickness 0.1524)
				)
				(justify mirror)
			)
		)
		(property "Value" ""
			(at 0 0 0)
			(layer "B.Fab")
			(effects
				(font
					(size 1.27 1.27)
				)
				(justify mirror)
			)
		)
		(duplicate_pad_numbers_are_jumpers no)
		(fp_line
			(start -1.03378 -1.284478)
			(end -1.03378 1.284478)
			(stroke
				(width 0.1524)
				(type default)
			)
			(layer "B.SilkS")
		)
		(fp_line
			(start -1.03378 1.284478)
			(end 1.03378 1.284478)
			(stroke
				(width 0.1524)
				(type default)
			)
			(layer "B.SilkS")
		)
		(fp_line
			(start 1.03378 -1.284478)
			(end -1.03378 -1.284478)
			(stroke
				(width 0.1524)
				(type default)
			)
			(layer "B.SilkS")
		)
		(fp_line
			(start 1.03378 1.284478)
			(end 1.03378 -1.284478)
			(stroke
				(width 0.1524)
				(type default)
			)
			(layer "B.SilkS")
		)
		(fp_poly
			(pts
				(xy 1.266698 -0.776732) (xy 1.871726 -0.474218) (xy 1.871726 -1.079246)
			)
			(stroke
				(width 0)
				(type default)
			)
			(fill yes)
			(layer "B.SilkS")
		)
		(fp_line
			(start -0.774954 -1.02489)
			(end -0.774954 1.02489)
			(stroke
				(width 0.1)
				(type default)
			)
			(layer "B.Fab")
		)
		(fp_line
			(start -0.774954 1.02489)
			(end 0.774954 1.02489)
			(stroke
				(width 0.1)
				(type default)
			)
			(layer "B.Fab")
		)
		(fp_line
			(start 0.774954 -1.02489)
			(end -0.774954 -1.02489)
			(stroke
				(width 0.1)
				(type default)
			)
			(layer "B.Fab")
		)
		(fp_line
			(start 0.774954 1.02489)
			(end 0.774954 -1.02489)
			(stroke
				(width 0.1)
				(type default)
			)
			(layer "B.Fab")
		)
		(fp_poly
			(pts
				(xy 1.201674 -0.750062) (xy 1.806702 -0.447548) (xy 1.806702 -1.052576)
			)
			(stroke
				(width 0)
				(type default)
			)
			(fill yes)
			(layer "B.Fab")
		)
		(pad "1" smd rect
			(at 0.64008 -0.750062 90)
			(size 0.3048 0.5334)
			(layers "B.Cu" "B.Mask" "B.Paste")
			(net "SMB_RT_CPU0_P2_ROM_MUX_1D_SCL")
		)
		(pad "2" smd rect
			(at 0.64008 -0.249936 90)
			(size 0.254 0.5334)
			(layers "B.Cu" "B.Mask" "B.Paste")
			(net "SMB_RT_CPU0_P2_ROM_MUX_1D_SDA")
		)
		(pad "3" smd rect
			(at 0.64008 0.249936 90)
			(size 0.254 0.5334)
			(layers "B.Cu" "B.Mask" "B.Paste")
			(net "SMB_RT_CPU0_P2_ROM_MUX_2D_SCL")
		)
		(pad "4" smd rect
			(at 0.64008 0.750062 90)
			(size 0.3048 0.5334)
			(layers "B.Cu" "B.Mask" "B.Paste")
			(net "SMB_RT_CPU0_P2_ROM_MUX_2D_SDA")
		)
		(pad "5" smd rect
			(at 0 0.839978 180)
			(size 0.3302 0.635)
			(layers "B.Cu" "B.Mask" "B.Paste")
			(net "GND")
		)
		(pad "6" smd rect
			(at -0.64008 0.750062 90)
			(size 0.3048 0.5334)
			(layers "B.Cu" "B.Mask" "B.Paste")
			(net "RT_ROM_MUX8_OE_N")
		)
		(pad "7" smd rect
			(at -0.64008 0.249936 90)
			(size 0.254 0.5334)
			(layers "B.Cu" "B.Mask" "B.Paste")
			(net "SMB_RT_CPU0_P2_ROM_R_SDA")
		)
		(pad "8" smd rect
			(at -0.64008 -0.249936 90)
			(size 0.254 0.5334)
			(layers "B.Cu" "B.Mask" "B.Paste")
			(net "SMB_RT_CPU0_P2_ROM_R_SCL")
		)
		(pad "9" smd rect
			(at -0.64008 -0.750062 90)
			(size 0.3048 0.5334)
			(layers "B.Cu" "B.Mask" "B.Paste")
			(net "FM_SMB_RT_ROM_MUX8_SEL")
		)
		(pad "10" smd rect
			(at 0 -0.839978 180)
			(size 0.3302 0.635)
			(layers "B.Cu" "B.Mask" "B.Paste")
			(net "P3V3_AUX")
		)
	)
	(footprint ""
		(layer "B.Cu")
		(at 347.008958 -254.06731 180)
		(property "Reference" "C2523"
			(at 0 0 0)
			(layer "B.SilkS")
			(hide yes)
			(effects
				(font
					(size 1.27 1.27)
				)
				(justify mirror)
			)
		)
		(property "Value" ""
			(at 0 0 0)
			(layer "B.Fab")
			(effects
				(font
					(size 1.27 1.27)
				)
				(justify mirror)
			)
		)
		(duplicate_pad_numbers_are_jumpers no)
		(fp_line
			(start 0.7874 0.4064)
			(end 0.7874 -0.4064)
			(stroke
				(width 0.1524)
				(type default)
			)
			(layer "B.SilkS")
		)
		(fp_line
			(start 0.7874 -0.4064)
			(end -0.7874 -0.4064)
			(stroke
				(width 0.1524)
				(type default)
			)
			(layer "B.SilkS")
		)
		(fp_line
			(start -0.7874 0.4064)
			(end 0.7874 0.4064)
			(stroke
				(width 0.1524)
				(type default)
			)
			(layer "B.SilkS")
		)
		(fp_line
			(start -0.7874 -0.4064)
			(end -0.7874 0.4064)
			(stroke
				(width 0.1524)
				(type default)
			)
			(layer "B.SilkS")
		)
		(fp_line
			(start 0.67945 0.3048)
			(end 0.67945 -0.305054)
			(stroke
				(width 0.1)
				(type default)
			)
			(layer "B.Fab")
		)
		(fp_line
			(start 0.67945 -0.305054)
			(end 0.12065 -0.305054)
			(stroke
				(width 0.1)
				(type default)
			)
			(layer "B.Fab")
		)
		(fp_line
			(start 0.12065 0.3048)
			(end 0.67945 0.3048)
			(stroke
				(width 0.1)
				(type default)
			)
			(layer "B.Fab")
		)
		(fp_line
			(start 0.12065 0.2794)
			(end 0.12065 0.3048)
			(stroke
				(width 0.1)
				(type default)
			)
			(layer "B.Fab")
		)
		(fp_line
			(start 0.12065 -0.2794)
			(end -0.12065 -0.2794)
			(stroke
				(width 0.1)
				(type default)
			)
			(layer "B.Fab")
		)
		(fp_line
			(start 0.12065 -0.305054)
			(end 0.12065 -0.2794)
			(stroke
				(width 0.1)
				(type default)
			)
			(layer "B.Fab")
		)
		(fp_line
			(start -0.120396 0.3048)
			(end -0.120396 0.2794)
			(stroke
				(width 0.1)
				(type default)
			)
			(layer "B.Fab")
		)
		(fp_line
			(start -0.120396 0.2794)
			(end 0.12065 0.2794)
			(stroke
				(width 0.1)
				(type default)
			)
			(layer "B.Fab")
		)
		(fp_line
			(start -0.12065 -0.2794)
			(end -0.12065 -0.3048)
			(stroke
				(width 0.1)
				(type default)
			)
			(layer "B.Fab")
		)
		(fp_line
			(start -0.12065 -0.3048)
			(end -0.67945 -0.3048)
			(stroke
				(width 0.1)
				(type default)
			)
			(layer "B.Fab")
		)
		(fp_line
			(start -0.67945 0.3048)
			(end -0.120396 0.3048)
			(stroke
				(width 0.1)
				(type default)
			)
			(layer "B.Fab")
		)
		(fp_line
			(start -0.67945 -0.3048)
			(end -0.67945 0.3048)
			(stroke
				(width 0.1)
				(type default)
			)
			(layer "B.Fab")
		)
		(pad "1" smd circle
			(at 0.40005 0)
			(size 0 0)
			(layers "B.Cu" "B.Mask" "B.Paste")
			(net "PVDD18_S5_P0")
		)
		(pad "2" smd circle
			(at -0.40005 0)
			(size 0 0)
			(layers "B.Cu" "B.Mask" "B.Paste")
			(net "GND")
		)
	)
	(footprint ""
		(layer "B.Cu")
		(at 64.191388 -390.560052 90)
		(property "Reference" "C258"
			(at 0 0 90)
			(layer "B.SilkS")
			(hide yes)
			(effects
				(font
					(size 1.27 1.27)
				)
				(justify mirror)
			)
		)
		(property "Value" ""
			(at 0 0 90)
			(layer "B.Fab")
			(effects
				(font
					(size 1.27 1.27)
				)
				(justify mirror)
			)
		)
		(duplicate_pad_numbers_are_jumpers no)
		(fp_line
			(start 0.7874 -0.4064)
			(end -0.7874 -0.4064)
			(stroke
				(width 0.1524)
				(type default)
			)
			(layer "B.SilkS")
		)
		(fp_line
			(start -0.7874 -0.4064)
			(end -0.7874 0.4064)
			(stroke
				(width 0.1524)
				(type default)
			)
			(layer "B.SilkS")
		)
		(fp_line
			(start 0.7874 0.4064)
			(end 0.7874 -0.4064)
			(stroke
				(width 0.1524)
				(type default)
			)
			(layer "B.SilkS")
		)
		(fp_line
			(start -0.7874 0.4064)
			(end 0.7874 0.4064)
			(stroke
				(width 0.1524)
				(type default)
			)
			(layer "B.SilkS")
		)
		(fp_line
			(start 0.67945 -0.305054)
			(end 0.12065 -0.305054)
			(stroke
				(width 0.1)
				(type default)
			)
			(layer "B.Fab")
		)
		(fp_line
			(start 0.12065 -0.305054)
			(end 0.12065 -0.2794)
			(stroke
				(width 0.1)
				(type default)
			)
			(layer "B.Fab")
		)
		(fp_line
			(start -0.12065 -0.3048)
			(end -0.67945 -0.3048)
			(stroke
				(width 0.1)
				(type default)
			)
			(layer "B.Fab")
		)
		(fp_line
			(start -0.67945 -0.3048)
			(end -0.67945 0.3048)
			(stroke
				(width 0.1)
				(type default)
			)
			(layer "B.Fab")
		)
		(fp_line
			(start 0.12065 -0.2794)
			(end -0.12065 -0.2794)
			(stroke
				(width 0.1)
				(type default)
			)
			(layer "B.Fab")
		)
		(fp_line
			(start -0.12065 -0.2794)
			(end -0.12065 -0.3048)
			(stroke
				(width 0.1)
				(type default)
			)
			(layer "B.Fab")
		)
		(fp_line
			(start 0.12065 0.2794)
			(end 0.12065 0.3048)
			(stroke
				(width 0.1)
				(type default)
			)
			(layer "B.Fab")
		)
		(fp_line
			(start -0.120396 0.2794)
			(end 0.12065 0.2794)
			(stroke
				(width 0.1)
				(type default)
			)
			(layer "B.Fab")
		)
		(fp_line
			(start 0.67945 0.3048)
			(end 0.67945 -0.305054)
			(stroke
				(width 0.1)
				(type default)
			)
			(layer "B.Fab")
		)
		(fp_line
			(start 0.12065 0.3048)
			(end 0.67945 0.3048)
			(stroke
				(width 0.1)
				(type default)
			)
			(layer "B.Fab")
		)
		(fp_line
			(start -0.120396 0.3048)
			(end -0.120396 0.2794)
			(stroke
				(width 0.1)
				(type default)
			)
			(layer "B.Fab")
		)
		(fp_line
			(start -0.67945 0.3048)
			(end -0.120396 0.3048)
			(stroke
				(width 0.1)
				(type default)
			)
			(layer "B.Fab")
		)
		(pad "1" smd circle
			(at 0.40005 0 270)
			(size 0 0)
			(layers "B.Cu" "B.Mask" "B.Paste")
			(net "P0V9_CPU1_RT0_2A")
		)
		(pad "2" smd circle
			(at -0.40005 0 270)
			(size 0 0)
			(layers "B.Cu" "B.Mask" "B.Paste")
			(net "GND")
		)
	)
)
